(kicad_pcb
	(version 20260206)
	(generator "pcbnew")
	(generator_version "10.0")
	(general
		(thickness 1.6)
		(legacy_teardrops no)
	)
	(paper "A4")
	(title_block
		(title "04192023_DAF0TMB3IC0_F0TG_MB_C_brd_V02_OCP.brd")
		(comment 1 "Grand Teton / footprints 4086-4092 of 8354")
	)
	(layers
		(0 "F.Cu" signal "TOP")
		(4 "In1.Cu" signal "GND")
		(6 "In2.Cu" signal "IN1")
		(8 "In3.Cu" signal "GND1")
		(10 "In4.Cu" signal "IN2")
		(12 "In5.Cu" signal "GND2")
		(14 "In6.Cu" signal "IN3")
		(16 "In7.Cu" signal "GND3")
		(18 "In8.Cu" signal "VCC")
		(20 "In9.Cu" signal "VCC1")
		(22 "In10.Cu" signal "GND4")
		(24 "In11.Cu" signal "IN4")
		(26 "In12.Cu" signal "GND5")
		(28 "In13.Cu" signal "IN5")
		(30 "In14.Cu" signal "GND6")
		(32 "In15.Cu" signal "IN6")
		(34 "In16.Cu" signal "GND7")
		(2 "B.Cu" signal "BOTTOM")
		(9 "F.Adhes" user "F.Adhesive")
		(11 "B.Adhes" user "B.Adhesive")
		(13 "F.Paste" user "Package Geometry/Pastemask Top")
		(15 "B.Paste" user "Package Geometry/Pastemask Bottom")
		(5 "F.SilkS" user "Ref Des/Silkscreen Top")
		(7 "B.SilkS" user "Ref Des/Silkscreen Bottom")
		(1 "F.Mask" user "Board Geometry/Soldermask Top")
		(3 "B.Mask" user "Board Geometry/Soldermask Bottom")
		(17 "Dwgs.User" user "User.Drawings")
		(19 "Cmts.User" user "User.Comments")
		(21 "Eco1.User" user "User.Eco1")
		(23 "Eco2.User" user "User.Eco2")
		(25 "Edge.Cuts" user "Board Geometry/Outline")
		(27 "Margin" user)
		(31 "F.CrtYd" user "Package Geometry/Place Bound Top")
		(29 "B.CrtYd" user "Package Geometry/Place Bound Bottom")
		(35 "F.Fab" user "Ref Des/Assembly Top")
		(33 "B.Fab" user "Ref Des/Assembly Bottom")
	)
	(footprint ""
		(layer "F.Cu")
		(at 367.004092 -381.41783 -90)
		(property "Reference" "C896"
			(at 0 0 270)
			(layer "F.SilkS")
			(hide yes)
			(effects
				(font
					(size 1.27 1.27)
				)
			)
		)
		(property "Value" ""
			(at 0 0 270)
			(layer "F.Fab")
			(effects
				(font
					(size 1.27 1.27)
				)
			)
		)
		(duplicate_pad_numbers_are_jumpers no)
		(fp_line
			(start -0.299974 0.150114)
			(end -0.299974 -0.150114)
			(stroke
				(width 0.1)
				(type default)
			)
			(layer "F.Fab")
		)
		(fp_line
			(start 0.299974 0.150114)
			(end -0.299974 0.150114)
			(stroke
				(width 0.1)
				(type default)
			)
			(layer "F.Fab")
		)
		(fp_line
			(start -0.299974 -0.150114)
			(end 0.299974 -0.150114)
			(stroke
				(width 0.1)
				(type default)
			)
			(layer "F.Fab")
		)
		(fp_line
			(start 0.299974 -0.150114)
			(end 0.299974 0.150114)
			(stroke
				(width 0.1)
				(type default)
			)
			(layer "F.Fab")
		)
		(pad "1" smd rect
			(at -0.2667 0 270)
			(size 0.3048 0.381)
			(layers "F.Cu" "F.Mask" "F.Paste")
			(net "P5E_CPU0_P3_TX_C_DN<2>")
		)
		(pad "2" smd rect
			(at 0.2667 0 270)
			(size 0.3048 0.381)
			(layers "F.Cu" "F.Mask" "F.Paste")
			(net "P5E_CPU0_P3_TX_DN<2>")
		)
	)
	(footprint ""
		(layer "F.Cu")
		(at 104.469946 -54.882034 90)
		(property "Reference" "R6319"
			(at 0 0 90)
			(layer "F.SilkS")
			(hide yes)
			(effects
				(font
					(size 1.27 1.27)
				)
			)
		)
		(property "Value" ""
			(at 0 0 90)
			(layer "F.Fab")
			(effects
				(font
					(size 1.27 1.27)
				)
			)
		)
		(duplicate_pad_numbers_are_jumpers no)
		(fp_line
			(start 0.7874 -0.4064)
			(end 0.7874 0.4064)
			(stroke
				(width 0.1524)
				(type default)
			)
			(layer "F.SilkS")
		)
		(fp_line
			(start -0.7874 -0.4064)
			(end 0.7874 -0.4064)
			(stroke
				(width 0.1524)
				(type default)
			)
			(layer "F.SilkS")
		)
		(fp_line
			(start 0.7874 0.4064)
			(end -0.7874 0.4064)
			(stroke
				(width 0.1524)
				(type default)
			)
			(layer "F.SilkS")
		)
		(fp_line
			(start -0.7874 0.4064)
			(end -0.7874 -0.4064)
			(stroke
				(width 0.1524)
				(type default)
			)
			(layer "F.SilkS")
		)
		(fp_line
			(start -0.12065 -0.305054)
			(end -0.12065 -0.2794)
			(stroke
				(width 0.1)
				(type default)
			)
			(layer "F.Fab")
		)
		(fp_line
			(start -0.67945 -0.305054)
			(end -0.12065 -0.305054)
			(stroke
				(width 0.1)
				(type default)
			)
			(layer "F.Fab")
		)
		(fp_line
			(start 0.67945 -0.3048)
			(end 0.67945 0.3048)
			(stroke
				(width 0.1)
				(type default)
			)
			(layer "F.Fab")
		)
		(fp_line
			(start 0.12065 -0.3048)
			(end 0.67945 -0.3048)
			(stroke
				(width 0.1)
				(type default)
			)
			(layer "F.Fab")
		)
		(fp_line
			(start 0.12065 -0.2794)
			(end 0.12065 -0.3048)
			(stroke
				(width 0.1)
				(type default)
			)
			(layer "F.Fab")
		)
		(fp_line
			(start -0.12065 -0.2794)
			(end 0.12065 -0.2794)
			(stroke
				(width 0.1)
				(type default)
			)
			(layer "F.Fab")
		)
		(fp_line
			(start 0.120396 0.2794)
			(end -0.12065 0.2794)
			(stroke
				(width 0.1)
				(type default)
			)
			(layer "F.Fab")
		)
		(fp_line
			(start -0.12065 0.2794)
			(end -0.12065 0.3048)
			(stroke
				(width 0.1)
				(type default)
			)
			(layer "F.Fab")
		)
		(fp_line
			(start 0.67945 0.3048)
			(end 0.120396 0.3048)
			(stroke
				(width 0.1)
				(type default)
			)
			(layer "F.Fab")
		)
		(fp_line
			(start 0.120396 0.3048)
			(end 0.120396 0.2794)
			(stroke
				(width 0.1)
				(type default)
			)
			(layer "F.Fab")
		)
		(fp_line
			(start -0.12065 0.3048)
			(end -0.67945 0.3048)
			(stroke
				(width 0.1)
				(type default)
			)
			(layer "F.Fab")
		)
		(fp_line
			(start -0.67945 0.3048)
			(end -0.67945 -0.305054)
			(stroke
				(width 0.1)
				(type default)
			)
			(layer "F.Fab")
		)
		(pad "1" smd circle
			(at -0.40005 0 90)
			(size 0 0)
			(layers "F.Cu" "F.Mask" "F.Paste")
			(net "USB_HUB2_TI_USB_VBUS")
		)
		(pad "2" smd circle
			(at 0.40005 0 90)
			(size 0 0)
			(layers "F.Cu" "F.Mask" "F.Paste")
			(net "GND")
		)
	)
	(footprint ""
		(layer "F.Cu")
		(at 141.29512 -31.62681 -90)
		(property "Reference" "C6015"
			(at 0 0 270)
			(layer "F.SilkS")
			(hide yes)
			(effects
				(font
					(size 1.27 1.27)
				)
			)
		)
		(property "Value" ""
			(at 0 0 270)
			(layer "F.Fab")
			(effects
				(font
					(size 1.27 1.27)
				)
			)
		)
		(duplicate_pad_numbers_are_jumpers no)
		(fp_line
			(start -0.40005 -0.4064)
			(end 0.40005 -0.4064)
			(stroke
				(width 0.1524)
				(type default)
			)
			(layer "F.SilkS")
		)
		(fp_line
			(start -0.6858 0.3048)
			(end -0.6858 -0.3048)
			(stroke
				(width 0.1)
				(type default)
			)
			(layer "F.Fab")
		)
		(fp_line
			(start -0.1016 0.3048)
			(end -0.6858 0.3048)
			(stroke
				(width 0.1)
				(type default)
			)
			(layer "F.Fab")
		)
		(fp_line
			(start 0.1016 0.3048)
			(end 0.1016 0.2794)
			(stroke
				(width 0.1)
				(type default)
			)
			(layer "F.Fab")
		)
		(fp_line
			(start 0.6858 0.3048)
			(end 0.1016 0.3048)
			(stroke
				(width 0.1)
				(type default)
			)
			(layer "F.Fab")
		)
		(fp_line
			(start -0.1016 0.2794)
			(end -0.1016 0.3048)
			(stroke
				(width 0.1)
				(type default)
			)
			(layer "F.Fab")
		)
		(fp_line
			(start 0.1016 0.2794)
			(end -0.1016 0.2794)
			(stroke
				(width 0.1)
				(type default)
			)
			(layer "F.Fab")
		)
		(fp_line
			(start -0.1016 -0.2794)
			(end 0.1016 -0.2794)
			(stroke
				(width 0.1)
				(type default)
			)
			(layer "F.Fab")
		)
		(fp_line
			(start 0.1016 -0.2794)
			(end 0.1016 -0.3048)
			(stroke
				(width 0.1)
				(type default)
			)
			(layer "F.Fab")
		)
		(fp_line
			(start -0.6858 -0.3048)
			(end -0.1016 -0.3048)
			(stroke
				(width 0.1)
				(type default)
			)
			(layer "F.Fab")
		)
		(fp_line
			(start -0.1016 -0.3048)
			(end -0.1016 -0.2794)
			(stroke
				(width 0.1)
				(type default)
			)
			(layer "F.Fab")
		)
		(fp_line
			(start 0.1016 -0.3048)
			(end 0.6858 -0.3048)
			(stroke
				(width 0.1)
				(type default)
			)
			(layer "F.Fab")
		)
		(fp_line
			(start 0.6858 -0.3048)
			(end 0.6858 0.3048)
			(stroke
				(width 0.1)
				(type default)
			)
			(layer "F.Fab")
		)
		(pad "1" smd rect
			(at -0.40005 0 90)
			(size 0.4572 0.508)
			(layers "F.Cu" "F.Mask" "F.Paste")
			(net "USB3_CPU0_BMC_RX_HUB1_DP")
		)
		(pad "2" smd rect
			(at 0.40005 0 90)
			(size 0.4572 0.508)
			(layers "F.Cu" "F.Mask" "F.Paste")
			(net "USB3_CPU0_BMC_RX_HUB_C_DP")
		)
	)
	(footprint ""
		(layer "F.Cu")
		(at 230.675688 -147.932648 180)
		(property "Reference" "C1519"
			(at 0 0 180)
			(layer "F.SilkS")
			(hide yes)
			(effects
				(font
					(size 1.27 1.27)
				)
			)
		)
		(property "Value" ""
			(at 0 0 180)
			(layer "F.Fab")
			(effects
				(font
					(size 1.27 1.27)
				)
			)
		)
		(duplicate_pad_numbers_are_jumpers no)
		(fp_line
			(start 0.7874 0.4064)
			(end -0.7874 0.4064)
			(stroke
				(width 0.1524)
				(type default)
			)
			(layer "F.SilkS")
		)
		(fp_line
			(start 0.7874 -0.4064)
			(end 0.7874 0.4064)
			(stroke
				(width 0.1524)
				(type default)
			)
			(layer "F.SilkS")
		)
		(fp_line
			(start -0.7874 0.4064)
			(end -0.7874 -0.4064)
			(stroke
				(width 0.1524)
				(type default)
			)
			(layer "F.SilkS")
		)
		(fp_line
			(start -0.7874 -0.4064)
			(end 0.7874 -0.4064)
			(stroke
				(width 0.1524)
				(type default)
			)
			(layer "F.SilkS")
		)
		(fp_line
			(start 0.67945 0.3048)
			(end 0.120396 0.3048)
			(stroke
				(width 0.1)
				(type default)
			)
			(layer "F.Fab")
		)
		(fp_line
			(start 0.67945 -0.3048)
			(end 0.67945 0.3048)
			(stroke
				(width 0.1)
				(type default)
			)
			(layer "F.Fab")
		)
		(fp_line
			(start 0.12065 -0.2794)
			(end 0.12065 -0.3048)
			(stroke
				(width 0.1)
				(type default)
			)
			(layer "F.Fab")
		)
		(fp_line
			(start 0.12065 -0.3048)
			(end 0.67945 -0.3048)
			(stroke
				(width 0.1)
				(type default)
			)
			(layer "F.Fab")
		)
		(fp_line
			(start 0.120396 0.3048)
			(end 0.120396 0.2794)
			(stroke
				(width 0.1)
				(type default)
			)
			(layer "F.Fab")
		)
		(fp_line
			(start 0.120396 0.2794)
			(end -0.12065 0.2794)
			(stroke
				(width 0.1)
				(type default)
			)
			(layer "F.Fab")
		)
		(fp_line
			(start -0.12065 0.3048)
			(end -0.67945 0.3048)
			(stroke
				(width 0.1)
				(type default)
			)
			(layer "F.Fab")
		)
		(fp_line
			(start -0.12065 0.2794)
			(end -0.12065 0.3048)
			(stroke
				(width 0.1)
				(type default)
			)
			(layer "F.Fab")
		)
		(fp_line
			(start -0.12065 -0.2794)
			(end 0.12065 -0.2794)
			(stroke
				(width 0.1)
				(type default)
			)
			(layer "F.Fab")
		)
		(fp_line
			(start -0.12065 -0.305054)
			(end -0.12065 -0.2794)
			(stroke
				(width 0.1)
				(type default)
			)
			(layer "F.Fab")
		)
		(fp_line
			(start -0.67945 0.3048)
			(end -0.67945 -0.305054)
			(stroke
				(width 0.1)
				(type default)
			)
			(layer "F.Fab")
		)
		(fp_line
			(start -0.67945 -0.305054)
			(end -0.12065 -0.305054)
			(stroke
				(width 0.1)
				(type default)
			)
			(layer "F.Fab")
		)
		(pad "1" smd circle
			(at -0.40005 0 180)
			(size 0 0)
			(layers "F.Cu" "F.Mask" "F.Paste")
			(net "PVDD18_S5_P0")
		)
		(pad "2" smd circle
			(at 0.40005 0 180)
			(size 0 0)
			(layers "F.Cu" "F.Mask" "F.Paste")
			(net "GND")
		)
	)
	(footprint ""
		(layer "F.Cu")
		(at 44.7294 -104.7369)
		(property "Reference" "R1052"
			(at 0 0 0)
			(layer "F.SilkS")
			(hide yes)
			(effects
				(font
					(size 1.27 1.27)
				)
			)
		)
		(property "Value" ""
			(at 0 0 0)
			(layer "F.Fab")
			(effects
				(font
					(size 1.27 1.27)
				)
			)
		)
		(duplicate_pad_numbers_are_jumpers no)
		(fp_line
			(start -0.7874 -0.4064)
			(end 0.7874 -0.4064)
			(stroke
				(width 0.1524)
				(type default)
			)
			(layer "F.SilkS")
		)
		(fp_line
			(start -0.7874 0.4064)
			(end -0.7874 -0.4064)
			(stroke
				(width 0.1524)
				(type default)
			)
			(layer "F.SilkS")
		)
		(fp_line
			(start 0.7874 -0.4064)
			(end 0.7874 0.4064)
			(stroke
				(width 0.1524)
				(type default)
			)
			(layer "F.SilkS")
		)
		(fp_line
			(start 0.7874 0.4064)
			(end -0.7874 0.4064)
			(stroke
				(width 0.1524)
				(type default)
			)
			(layer "F.SilkS")
		)
		(fp_line
			(start -0.67945 -0.305054)
			(end -0.12065 -0.305054)
			(stroke
				(width 0.1)
				(type default)
			)
			(layer "F.Fab")
		)
		(fp_line
			(start -0.67945 0.3048)
			(end -0.67945 -0.305054)
			(stroke
				(width 0.1)
				(type default)
			)
			(layer "F.Fab")
		)
		(fp_line
			(start -0.12065 -0.305054)
			(end -0.12065 -0.2794)
			(stroke
				(width 0.1)
				(type default)
			)
			(layer "F.Fab")
		)
		(fp_line
			(start -0.12065 -0.2794)
			(end 0.12065 -0.2794)
			(stroke
				(width 0.1)
				(type default)
			)
			(layer "F.Fab")
		)
		(fp_line
			(start -0.12065 0.2794)
			(end -0.12065 0.3048)
			(stroke
				(width 0.1)
				(type default)
			)
			(layer "F.Fab")
		)
		(fp_line
			(start -0.12065 0.3048)
			(end -0.67945 0.3048)
			(stroke
				(width 0.1)
				(type default)
			)
			(layer "F.Fab")
		)
		(fp_line
			(start 0.120396 0.2794)
			(end -0.12065 0.2794)
			(stroke
				(width 0.1)
				(type default)
			)
			(layer "F.Fab")
		)
		(fp_line
			(start 0.120396 0.3048)
			(end 0.120396 0.2794)
			(stroke
				(width 0.1)
				(type default)
			)
			(layer "F.Fab")
		)
		(fp_line
			(start 0.12065 -0.3048)
			(end 0.67945 -0.3048)
			(stroke
				(width 0.1)
				(type default)
			)
			(layer "F.Fab")
		)
		(fp_line
			(start 0.12065 -0.2794)
			(end 0.12065 -0.3048)
			(stroke
				(width 0.1)
				(type default)
			)
			(layer "F.Fab")
		)
		(fp_line
			(start 0.67945 -0.3048)
			(end 0.67945 0.3048)
			(stroke
				(width 0.1)
				(type default)
			)
			(layer "F.Fab")
		)
		(fp_line
			(start 0.67945 0.3048)
			(end 0.120396 0.3048)
			(stroke
				(width 0.1)
				(type default)
			)
			(layer "F.Fab")
		)
		(pad "1" smd circle
			(at -0.40005 0)
			(size 0 0)
			(layers "F.Cu" "F.Mask" "F.Paste")
			(net "P3V3_AUX")
		)
		(pad "2" smd circle
			(at 0.40005 0)
			(size 0 0)
			(layers "F.Cu" "F.Mask" "F.Paste")
			(net "P3V3_AUX_DSC_G1")
		)
	)
	(footprint ""
		(layer "F.Cu")
		(at 173.609 -100.294948 -90)
		(property "Reference" "R6008"
			(at 0 0 270)
			(layer "F.SilkS")
			(hide yes)
			(effects
				(font
					(size 1.27 1.27)
				)
			)
		)
		(property "Value" ""
			(at 0 0 270)
			(layer "F.Fab")
			(effects
				(font
					(size 1.27 1.27)
				)
			)
		)
		(duplicate_pad_numbers_are_jumpers no)
		(fp_line
			(start -0.7874 0.4064)
			(end -0.7874 -0.4064)
			(stroke
				(width 0.1524)
				(type default)
			)
			(layer "F.SilkS")
		)
		(fp_line
			(start 0.7874 0.4064)
			(end -0.7874 0.4064)
			(stroke
				(width 0.1524)
				(type default)
			)
			(layer "F.SilkS")
		)
		(fp_line
			(start -0.7874 -0.4064)
			(end 0.7874 -0.4064)
			(stroke
				(width 0.1524)
				(type default)
			)
			(layer "F.SilkS")
		)
		(fp_line
			(start 0.7874 -0.4064)
			(end 0.7874 0.4064)
			(stroke
				(width 0.1524)
				(type default)
			)
			(layer "F.SilkS")
		)
		(fp_line
			(start -0.67945 0.3048)
			(end -0.67945 -0.305054)
			(stroke
				(width 0.1)
				(type default)
			)
			(layer "F.Fab")
		)
		(fp_line
			(start -0.12065 0.3048)
			(end -0.67945 0.3048)
			(stroke
				(width 0.1)
				(type default)
			)
			(layer "F.Fab")
		)
		(fp_line
			(start 0.120396 0.3048)
			(end 0.120396 0.2794)
			(stroke
				(width 0.1)
				(type default)
			)
			(layer "F.Fab")
		)
		(fp_line
			(start 0.67945 0.3048)
			(end 0.120396 0.3048)
			(stroke
				(width 0.1)
				(type default)
			)
			(layer "F.Fab")
		)
		(fp_line
			(start -0.12065 0.2794)
			(end -0.12065 0.3048)
			(stroke
				(width 0.1)
				(type default)
			)
			(layer "F.Fab")
		)
		(fp_line
			(start 0.120396 0.2794)
			(end -0.12065 0.2794)
			(stroke
				(width 0.1)
				(type default)
			)
			(layer "F.Fab")
		)
		(fp_line
			(start -0.12065 -0.2794)
			(end 0.12065 -0.2794)
			(stroke
				(width 0.1)
				(type default)
			)
			(layer "F.Fab")
		)
		(fp_line
			(start 0.12065 -0.2794)
			(end 0.12065 -0.3048)
			(stroke
				(width 0.1)
				(type default)
			)
			(layer "F.Fab")
		)
		(fp_line
			(start 0.12065 -0.3048)
			(end 0.67945 -0.3048)
			(stroke
				(width 0.1)
				(type default)
			)
			(layer "F.Fab")
		)
		(fp_line
			(start 0.67945 -0.3048)
			(end 0.67945 0.3048)
			(stroke
				(width 0.1)
				(type default)
			)
			(layer "F.Fab")
		)
		(fp_line
			(start -0.67945 -0.305054)
			(end -0.12065 -0.305054)
			(stroke
				(width 0.1)
				(type default)
			)
			(layer "F.Fab")
		)
		(fp_line
			(start -0.12065 -0.305054)
			(end -0.12065 -0.2794)
			(stroke
				(width 0.1)
				(type default)
			)
			(layer "F.Fab")
		)
		(pad "1" smd circle
			(at -0.40005 0 270)
			(size 0 0)
			(layers "F.Cu" "F.Mask" "F.Paste")
			(net "SGPIO_SCM_DO_<0>")
		)
		(pad "2" smd circle
			(at 0.40005 0 270)
			(size 0 0)
			(layers "F.Cu" "F.Mask" "F.Paste")
			(net "SGPIO_SCM_DO_R_<0>")
		)
	)
	(footprint ""
		(layer "F.Cu")
		(at 422.339516 -356.32644 180)
		(property "Reference" "PR133"
			(at 0 0 180)
			(layer "F.SilkS")
			(hide yes)
			(effects
				(font
					(size 1.27 1.27)
				)
			)
		)
		(property "Value" ""
			(at 0 0 180)
			(layer "F.Fab")
			(effects
				(font
					(size 1.27 1.27)
				)
			)
		)
		(duplicate_pad_numbers_are_jumpers no)
		(fp_line
			(start 0.7874 0.4064)
			(end -0.7874 0.4064)
			(stroke
				(width 0.1524)
				(type default)
			)
			(layer "F.SilkS")
		)
		(fp_line
			(start 0.7874 -0.4064)
			(end 0.7874 0.4064)
			(stroke
				(width 0.1524)
				(type default)
			)
			(layer "F.SilkS")
		)
		(fp_line
			(start -0.7874 0.4064)
			(end -0.7874 -0.4064)
			(stroke
				(width 0.1524)
				(type default)
			)
			(layer "F.SilkS")
		)
		(fp_line
			(start -0.7874 -0.4064)
			(end 0.7874 -0.4064)
			(stroke
				(width 0.1524)
				(type default)
			)
			(layer "F.SilkS")
		)
		(fp_line
			(start 0.67945 0.3048)
			(end 0.120396 0.3048)
			(stroke
				(width 0.1)
				(type default)
			)
			(layer "F.Fab")
		)
		(fp_line
			(start 0.67945 -0.3048)
			(end 0.67945 0.3048)
			(stroke
				(width 0.1)
				(type default)
			)
			(layer "F.Fab")
		)
		(fp_line
			(start 0.12065 -0.2794)
			(end 0.12065 -0.3048)
			(stroke
				(width 0.1)
				(type default)
			)
			(layer "F.Fab")
		)
		(fp_line
			(start 0.12065 -0.3048)
			(end 0.67945 -0.3048)
			(stroke
				(width 0.1)
				(type default)
			)
			(layer "F.Fab")
		)
		(fp_line
			(start 0.120396 0.3048)
			(end 0.120396 0.2794)
			(stroke
				(width 0.1)
				(type default)
			)
			(layer "F.Fab")
		)
		(fp_line
			(start 0.120396 0.2794)
			(end -0.12065 0.2794)
			(stroke
				(width 0.1)
				(type default)
			)
			(layer "F.Fab")
		)
		(fp_line
			(start -0.12065 0.3048)
			(end -0.67945 0.3048)
			(stroke
				(width 0.1)
				(type default)
			)
			(layer "F.Fab")
		)
		(fp_line
			(start -0.12065 0.2794)
			(end -0.12065 0.3048)
			(stroke
				(width 0.1)
				(type default)
			)
			(layer "F.Fab")
		)
		(fp_line
			(start -0.12065 -0.2794)
			(end 0.12065 -0.2794)
			(stroke
				(width 0.1)
				(type default)
			)
			(layer "F.Fab")
		)
		(fp_line
			(start -0.12065 -0.305054)
			(end -0.12065 -0.2794)
			(stroke
				(width 0.1)
				(type default)
			)
			(layer "F.Fab")
		)
		(fp_line
			(start -0.67945 0.3048)
			(end -0.67945 -0.305054)
			(stroke
				(width 0.1)
				(type default)
			)
			(layer "F.Fab")
		)
		(fp_line
			(start -0.67945 -0.305054)
			(end -0.12065 -0.305054)
			(stroke
				(width 0.1)
				(type default)
			)
			(layer "F.Fab")
		)
		(pad "1" smd circle
			(at -0.40005 0 180)
			(size 0 0)
			(layers "F.Cu" "F.Mask" "F.Paste")
			(net "GND")
		)
		(pad "2" smd circle
			(at 0.40005 0 180)
			(size 0 0)
			(layers "F.Cu" "F.Mask" "F.Paste")
			(net "PVDD11_S3_P0_LSET1")
		)
	)
)
